FILE_TYPE = MULTI_PHYS_TABLE;

PART 'PCA9508DP_TSSOP8'
CLASS=IC

{========================================================================================}
:CLS_PN             = JEDEC_TYPE          | ALT_SYMBOLS           | DESCRIPTION                                                             | CPN_STATUS ;
{========================================================================================}
 'G220-10282-01'    = 'SOP8_118_P0256_V2' | '(SOP8_118_P0256_V2)' | 'IC, PCA9508, HOT SWAPPABLE LEVEL TRANSLATING I2C-BUS REPEATER, TSSOP8' | ''        
 'G220-10219-01'    = 'SOP8_118_P0256_V2' | '(SOP8_118_P0256_V2)' | 'IC,I2C/SMBUS_REPEATER,TSSOP8'                                          | 'NFND'        
 'G223-10063-01'    = 'SOP8_154X193_P050' | '(SOP8_154X193_P050)' | 'IC,NXP_PCA9517AD,I2C/SMBUS_REPEATER,SO8'                               | 'NFND'        
 'G223-10278-01'    = 'SOP8_118_P0256_V2' | '(SOP8_118_P0256_V2)' | 'IC,I2C,REPEATER,9617A,0.8~5.5V,2.2~5.5V,MSOP8'                         | 'PREFERRED'        

END_PART

END.

